# SCM (Grand Teton) — schematic netlist excerpt (pin names and nets, part order shuffled) for the footprints in the layout excerpt that follows; sources: Cadence DE-HDL packaged netlist, KiCad conversion of 12092022_DA0F0TMDCD0_F0T_Management_Board_D_brd_V3_OCP.brd

R839  Q_RES  8.2K 5% CHIP  pkg 0402LF  page 49 : A = PWR_LED ; B = GND

U44  SN74LVC1G07DCKR  IC  pkg SC70-5XB  page 25
  NC1  = NC
  A  = RST_SPI_FLASH_R_N
  GND  = GND
  Y  = RST_SPI_FLASH_BUF_R3_N
  VCC  = P3V3_AUX

(kicad_pcb
	(version 20260206)
	(generator "pcbnew")
	(generator_version "10.0")
	(general
		(thickness 1.6)
		(legacy_teardrops no)
	)
	(paper "A4")
	(title_block
		(title "12092022_DA0F0TMDCD0_F0T_Management_Board_D_brd_V3_OCP.brd")
		(comment 1 "Grand Teton / footprints 21-22 of 1440")
	)
	(layers
		(0 "F.Cu" signal "TOP")
		(4 "In1.Cu" signal "GND")
		(6 "In2.Cu" signal "IN1")
		(8 "In3.Cu" signal "GND1")
		(10 "In4.Cu" signal "IN2")
		(12 "In5.Cu" signal "VCC")
		(14 "In6.Cu" signal "VCC1")
		(16 "In7.Cu" signal "IN3")
		(18 "In8.Cu" signal "GND2")
		(20 "In9.Cu" signal "IN4")
		(22 "In10.Cu" signal "GND3")
		(2 "B.Cu" signal "BOTTOM")
		(9 "F.Adhes" user "F.Adhesive")
		(11 "B.Adhes" user "B.Adhesive")
		(13 "F.Paste" user "Package Geometry/Pastemask Top")
		(15 "B.Paste" user "Package Geometry/Pastemask Bottom")
		(5 "F.SilkS" user "Ref Des/Silkscreen Top")
		(7 "B.SilkS" user "Ref Des/Silkscreen Bottom")
		(1 "F.Mask" user "Board Geometry/Soldermask Top")
		(3 "B.Mask" user "Board Geometry/Soldermask Bottom")
		(17 "Dwgs.User" user "User.Drawings")
		(19 "Cmts.User" user "User.Comments")
		(21 "Eco1.User" user "User.Eco1")
		(23 "Eco2.User" user "User.Eco2")
		(25 "Edge.Cuts" user "Board Geometry/Outline")
		(27 "Margin" user)
		(31 "F.CrtYd" user "Package Geometry/Place Bound Top")
		(29 "B.CrtYd" user "Package Geometry/Place Bound Bottom")
		(35 "F.Fab" user "Ref Des/Assembly Top")
		(33 "B.Fab" user "Ref Des/Assembly Bottom")
	)
	(footprint ""
		(layer "F.Cu")
		(at 13.335 -18.161 -90)
		(property "Reference" "R839"
			(at 0 0 270)
			(layer "F.SilkS")
			(hide yes)
			(effects
				(font
					(size 1.27 1.27)
				)
			)
		)
		(property "Value" ""
			(at 0 0 270)
			(layer "F.Fab")
			(effects
				(font
					(size 1.27 1.27)
				)
			)
		)
		(duplicate_pad_numbers_are_jumpers no)
		(fp_line
			(start -0.7874 0.4064)
			(end -0.7874 -0.4064)
			(stroke
				(width 0.1524)
				(type default)
			)
			(layer "F.SilkS")
		)
		(fp_line
			(start 0.7874 0.4064)
			(end -0.7874 0.4064)
			(stroke
				(width 0.1524)
				(type default)
			)
			(layer "F.SilkS")
		)
		(fp_line
			(start -0.7874 -0.4064)
			(end 0.7874 -0.4064)
			(stroke
				(width 0.1524)
				(type default)
			)
			(layer "F.SilkS")
		)
		(fp_line
			(start 0.7874 -0.4064)
			(end 0.7874 0.4064)
			(stroke
				(width 0.1524)
				(type default)
			)
			(layer "F.SilkS")
		)
		(fp_line
			(start -0.67945 0.3048)
			(end -0.67945 -0.305054)
			(stroke
				(width 0.1)
				(type default)
			)
			(layer "F.Fab")
		)
		(fp_line
			(start -0.12065 0.3048)
			(end -0.67945 0.3048)
			(stroke
				(width 0.1)
				(type default)
			)
			(layer "F.Fab")
		)
		(fp_line
			(start 0.120396 0.3048)
			(end 0.120396 0.2794)
			(stroke
				(width 0.1)
				(type default)
			)
			(layer "F.Fab")
		)
		(fp_line
			(start 0.67945 0.3048)
			(end 0.120396 0.3048)
			(stroke
				(width 0.1)
				(type default)
			)
			(layer "F.Fab")
		)
		(fp_line
			(start -0.12065 0.2794)
			(end -0.12065 0.3048)
			(stroke
				(width 0.1)
				(type default)
			)
			(layer "F.Fab")
		)
		(fp_line
			(start 0.120396 0.2794)
			(end -0.12065 0.2794)
			(stroke
				(width 0.1)
				(type default)
			)
			(layer "F.Fab")
		)
		(fp_line
			(start -0.12065 -0.2794)
			(end 0.12065 -0.2794)
			(stroke
				(width 0.1)
				(type default)
			)
			(layer "F.Fab")
		)
		(fp_line
			(start 0.12065 -0.2794)
			(end 0.12065 -0.3048)
			(stroke
				(width 0.1)
				(type default)
			)
			(layer "F.Fab")
		)
		(fp_line
			(start 0.12065 -0.3048)
			(end 0.67945 -0.3048)
			(stroke
				(width 0.1)
				(type default)
			)
			(layer "F.Fab")
		)
		(fp_line
			(start 0.67945 -0.3048)
			(end 0.67945 0.3048)
			(stroke
				(width 0.1)
				(type default)
			)
			(layer "F.Fab")
		)
		(fp_line
			(start -0.67945 -0.305054)
			(end -0.12065 -0.305054)
			(stroke
				(width 0.1)
				(type default)
			)
			(layer "F.Fab")
		)
		(fp_line
			(start -0.12065 -0.305054)
			(end -0.12065 -0.2794)
			(stroke
				(width 0.1)
				(type default)
			)
			(layer "F.Fab")
		)
		(pad "1" smd circle
			(at -0.40005 0 270)
			(size 0 0)
			(layers "F.Cu" "F.Mask" "F.Paste")
			(net "PWR_LED")
		)
		(pad "2" smd circle
			(at 0.40005 0 270)
			(size 0 0)
			(layers "F.Cu" "F.Mask" "F.Paste")
			(net "GND")
		)
	)
	(footprint ""
		(layer "F.Cu")
		(at 17.47774 -42.72534 90)
		(property "Reference" "U44"
			(at -0.94234 -1.70307 90)
			(unlocked yes)
			(layer "F.SilkS")
			(effects
				(font
					(size 0.7874 0.5842)
					(thickness 0.1524)
				)
				(justify left)
			)
		)
		(property "Value" ""
			(at 0 0 90)
			(layer "F.Fab")
			(effects
				(font
					(size 1.27 1.27)
				)
			)
		)
		(duplicate_pad_numbers_are_jumpers no)
		(fp_line
			(start 1.684274 -1.074928)
			(end 1.684274 1.074928)
			(stroke
				(width 0.1524)
				(type default)
			)
			(layer "F.SilkS")
		)
		(fp_line
			(start 0.381 -1.074928)
			(end 1.684274 -1.074928)
			(stroke
				(width 0.1524)
				(type default)
			)
			(layer "F.SilkS")
		)
		(fp_line
			(start -0.381 -1.074928)
			(end 0 -0.625094)
			(stroke
				(width 0.1524)
				(type default)
			)
			(layer "F.SilkS")
		)
		(fp_line
			(start -1.684274 -1.074928)
			(end -0.381 -1.074928)
			(stroke
				(width 0.1524)
				(type default)
			)
			(layer "F.SilkS")
		)
		(fp_line
			(start 0 -0.625094)
			(end 0.381 -1.074928)
			(stroke
				(width 0.1524)
				(type default)
			)
			(layer "F.SilkS")
		)
		(fp_line
			(start 1.684274 1.074928)
			(end -1.684274 1.074928)
			(stroke
				(width 0.1524)
				(type default)
			)
			(layer "F.SilkS")
		)
		(fp_line
			(start -1.684274 1.074928)
			(end -1.684274 -1.074928)
			(stroke
				(width 0.1524)
				(type default)
			)
			(layer "F.SilkS")
		)
		(fp_poly
			(pts
				(xy -2.637282 -0.903986) (xy -2.637282 -0.395986) (xy -1.875282 -0.649986)
			)
			(stroke
				(width 0)
				(type default)
			)
			(fill yes)
			(layer "F.SilkS")
		)
		(fp_line
			(start 0.700024 -1.074928)
			(end -0.700024 -1.074928)
			(stroke
				(width 0.1)
				(type default)
			)
			(layer "F.Fab")
		)
		(fp_line
			(start -0.700024 -1.074928)
			(end -0.700024 1.074928)
			(stroke
				(width 0.1)
				(type default)
			)
			(layer "F.Fab")
		)
		(fp_line
			(start 0.700024 1.074928)
			(end 0.700024 -1.074928)
			(stroke
				(width 0.1)
				(type default)
			)
			(layer "F.Fab")
		)
		(fp_line
			(start -0.700024 1.074928)
			(end 0.700024 1.074928)
			(stroke
				(width 0.1)
				(type default)
			)
			(layer "F.Fab")
		)
		(fp_poly
			(pts
				(xy -2.637282 -0.903986) (xy -2.637282 -0.395986) (xy -1.875282 -0.649986)
			)
			(stroke
				(width 0)
				(type default)
			)
			(fill yes)
			(layer "F.Fab")
		)
		(pad "1" smd rect
			(at -1.100074 -0.649986)
			(size 0.4064 0.9144)
			(layers "F.Cu" "F.Mask" "F.Paste")
			(net "Net_1197")
		)
		(pad "2" smd rect
			(at -1.100074 0)
			(size 0.4064 0.9144)
			(layers "F.Cu" "F.Mask" "F.Paste")
			(net "RST_SPI_FLASH_R_N")
		)
		(pad "3" smd rect
			(at -1.100074 0.649986)
			(size 0.4064 0.9144)
			(layers "F.Cu" "F.Mask" "F.Paste")
			(net "GND")
		)
		(pad "4" smd rect
			(at 1.100074 0.649986)
			(size 0.4064 0.9144)
			(layers "F.Cu" "F.Mask" "F.Paste")
			(net "RST_SPI_FLASH_BUF_R3_N")
		)
		(pad "5" smd rect
			(at 1.100074 -0.649986)
			(size 0.4064 0.9144)
			(layers "F.Cu" "F.Mask" "F.Paste")
			(net "P3V3_AUX")
		)
	)
)
